# ZAIUS-MB-EVT3-HW-EBOM-X00_20161228-add_2nd_source_X15-20170106-Final.xls — TLA (bom)
| FOXCONN TECHNOLOGY GROUP |  |  |  |  |  |  |  |  |  |
| BILL OF MATERIAL |  |  |  |  |  |  |  |  |  |
| AA P/N | 1A42DLU00-600-G | CUSTOMER | <name> | Customer P/N | 42001726-02 | Product Code |  |  |  |
| PWA P/N |  | PWA DESCRIPTION | ASSY,MB,G_ZAIUS |  |  | PWA REV | X02 | Prepared By SE |  |
| Item | FOXCONN P/N | Customer P/N | Part Description | Manufacturer  Full Name | Manufacturer  Part Number | Qty | RoHS Status | Location | Remark |
| 1 | 1A424CJ00-600-G |  | LOAD FRAME ASM,ZNEW,IBM,01AF120,G,00 | FOXCONN / EPD5 | 1A424CJ00-600-G | 2 | G |  | Rev:A IBM PN:01AF120 |
| 2 | 1A424CG00-600-G |  | LOAD FRAME ASM,ZNEW,IBM,01AF118,G,00 | FOXCONN / EPD5 | 1A424CG00-600-G | 2 | G |  | Rev:A IBM PN:01AF118 |
| 3 | 2A584VU00-192-G |  | BACKPLATE SCREW | Supply Technologies | 46K4434 | 8 | G |  | Rev:A |
| 4 | 1A42FV700-13E-G |  | Power 9 CPU Backplate (Combined with Mylar and Dowel) | Aavid | 360493 | 2 | G |  | Rev:A (Reference IBM PN:01AF136) |
|  | 1A42FL600-H8U-G |  | Power 9 CPU Backplate (Combined with Mylar and Dowel) ; 2nd | Furukawa | HS855380 |  | G |  | Rev:B |
| 5 | 7J-004-938 |  | L6 LABEL ( 12.7*11.1mm) | FOXCONN / EPD1 | 7J-004-938 | 1 | G |  | ID label. |
| 6 | 1A42EG100-653-G |  | Switch CAP blue. | DIPTRONICS | KTSC-62B | 1 | G |  | Rev:H Color Blue for Power button. Power Button should go to the left (or above) the Reset button. |
| 7 | 1A42EGF00-653-G |  | Switch CAP black. | DIPTRONICS | KTSC-62K | 1 | G |  | Rev:H Color Black for Reset button. |
| 8 | 48011U800-13E-G |  | Heat sink (40x80x25mm) | Aavid | 360579 | 2 | G |  | Locked for EVT3 only. Rev:X01 For VTM-1 |
|  | 48011U100-H8U-G |  | Heat sink (40x80x25mm) 2nd | Furukawa | HS855360 |  | G |  | Locked  for EVT3 only. Rev:B For VTM-1 |
| 9 | 48011U700-13E-G |  | Heat sink (80x57.3x32.6mm) | Aavid | 360580 | 2 | G |  | Rev:X01 For VTM-2 |
|  | 48011TU00-H8U-G |  | Heat sink (80x57.3x32.6mm) 2nd | Furukawa | HS855370 |  | G |  | Rev:C For VTM-2 |
| 10 | 2A1501R00-HE9-G |  | SPACER H:6.6MM, THICKNESS:3.0MM | KANG YANG | ULCO6.6-3.1(GR) | 1 | G |  | Rev:A FOR M.2 CARD |
| 11 | 7B3272600-HE9-G |  | SPACER H:12MM, THICKNESS:3.0MM | KANG YANG | MSPD-12L | 4 | G |  | Rev:A FOR OCP CARD |
| 12 | 7B3272500-HE9-G |  | SPACER H:9MM, THICKNESS:3.0MM | KANG YANG | MSPD-9L | 1 | G |  | Rev:A FOR LV CARD |
| 13 | 7J-004-1582 |  | Label 1.25" (31.75mm) x 0.5"(6.35mm) | FOXCONN / EPD1 | 7J-004-1582 | 2 | G |  | For customer PN & SN label requirement. |
| 14 | 7D061F800-H60-G |  | Rubber OD=4.0mm , L=4.5mm | Pingood | R0404-SGB | 2 | G |  | Rev:2A For Heat sink VTM-2 |
| 15 | 7J-004-1027 |  | LBL,ADRS,MAC (16 x 16 mm) | FOXCONN / EPD1 | 7J-004-1027 | 1 | G |  | For LOM, BMC, NCSI |
